# T6G (Grand Teton) — schematic netlist excerpt (pin names and nets, part order shuffled) for the footprints in the layout excerpt that follows; sources: Cadence DE-HDL packaged netlist, KiCad conversion of 04192023_DAF0TMB3IC0_F0TG_MB_C_brd_V02_OCP.brd

J28  SCONN288_DDR506112002KQ  IO  pkg DDR288S_1-1VXC  page 100
  VIN_BULK0  = P12V_MEM_CPU1
  RFU0  = NC
  VIN_MGMT  = P3V3_AUX
  HSCL  = I3C_SPD_DDRC_CPU1_SCL
  HSDA  = I3C_SPD_DDRC_CPU1_SDA
  VSS0  = GND
  DQ0_A  = M_C_CPU1_SA_DQ<0>
  VSS1  = GND
  DQ1_A  = M_C_CPU1_SA_DQ<1>
  VSS2  = GND
  DQS0_A_T  = M_C_CPU1_SA_DQS_DP<0>
  DQS0_A_C  = M_C_CPU1_SA_DQS_DN<0>
  VSS3  = GND
  DQ4_A  = M_C_CPU1_SA_DQ<4>
  VSS4  = GND
  DQ5_A  = M_C_CPU1_SA_DQ<5>
  VSS5  = GND
  DQ8_A  = M_C_CPU1_SA_DQ<8>
  VSS6  = GND
  DQ9_A  = M_C_CPU1_SA_DQ<9>
  VSS7  = GND
  DQS1_A_T  = M_C_CPU1_SA_DQS_DP<1>
  DQS1_A_C  = M_C_CPU1_SA_DQS_DN<1>
  VSS8  = GND
  DQ12_A  = M_C_CPU1_SA_DQ<12>
  VSS9  = GND
  DQ13_A  = M_C_CPU1_SA_DQ<13>
  VSS10  = GND
  DQ16_A  = M_C_CPU1_SA_DQ<16>
  VSS11  = GND
  DQ17_A  = M_C_CPU1_SA_DQ<17>
  VSS12  = GND
  DQS2_A_T  = M_C_CPU1_SA_DQS_DP<2>
  DQS2_A_C  = M_C_CPU1_SA_DQS_DN<2>
  VSS13  = GND
  DQ20_A  = M_C_CPU1_SA_DQ<20>
  VSS14  = GND
  DQ21_A  = M_C_CPU1_SA_DQ<21>
  VSS15  = GND
  DQ24_A  = M_C_CPU1_SA_DQ<24>
  VSS16  = GND
  DQ25_A  = M_C_CPU1_SA_DQ<25>
  VSS17  = GND
  DQS3_A_T  = M_C_CPU1_SA_DQS_DP<3>
  DQS3_A_C  = M_C_CPU1_SA_DQS_DN<3>
  VSS18  = GND
  DQ28_A  = M_C_CPU1_SA_DQ<28>
  VSS19  = GND
  DQ29_A  = M_C_CPU1_SA_DQ<29>
  VSS20  = GND
  CB0_A  = M_C_CPU1_SA_CB<0>
  VSS21  = GND
  CB1_A  = M_C_CPU1_SA_CB<1>
  VSS22  = GND
  DQS4_A_T  = M_C_CPU1_SA_DQS_DP<4>
  DQS4_A_C  = M_C_CPU1_SA_DQS_DN<4>
  VSS23  = GND
  CB4_A  = M_C_CPU1_SA_CB<4>
  VSS24  = GND
  CB5_A  = M_C_CPU1_SA_CB<5>
  VSS25  = GND
  ALERT_N  = M_C_CPU1_ALERT_N
  VSS26  = GND
  CS0_A_N  = M_C_CPU1_SA_CS_N<0>
  VSS27  = GND
  CA0_A  = M_C_CPU1_SA_CA<0>
  VSS28  = GND
  CA2_A  = M_C_CPU1_SA_CA<2>
  VSS29  = GND
  CA4_A  = M_C_CPU1_SA_CA<4>
  VSS30  = GND
  CA6_A  = M_C_CPU1_SA_CA<6>
  VSS31  = GND
  PAR_A  = M_C_CPU1_SA_PAR
  VSS32  = GND
  CA0_B  = M_C_CPU1_SB_CA<0>
  VSS33  = GND
  CA2_B  = M_C_CPU1_SB_CA<2>
  VSS34  = GND
  CA4_B  = M_C_CPU1_SB_CA<4>
  VSS35  = GND
  CA6_B  = M_C_CPU1_SB_CA<6>
  VSS36  = GND
  CS0_B_N  = M_C_CPU1_SB_CS_N<0>
  VSS37  = GND
  \lbd||rsp_a_n\  = M_C_CPU1_SA_RSP<0>
  \lbs||rsp_b_n\  = M_C_CPU1_SB_RSP<0>
  VSS38  = GND
  CB4_B  = M_C_CPU1_SB_CB<4>
  VSS39  = GND
  CB5_B  = M_C_CPU1_SB_CB<5>
  VSS40  = GND
  \dqs9_b_t||tdqs9_b_t||dbi4_b_n\  = M_C_CPU1_SB_DQS_DP<9>
  \dqs9_b_c||tdqs9_b_c\  = M_C_CPU1_SB_DQS_DN<9>
  VSS41  = GND
  CB0_B  = M_C_CPU1_SB_CB<0>
  VSS42  = GND
  CB1_B  = M_C_CPU1_SB_CB<1>
  VSS43  = GND
  DQ0_B  = M_C_CPU1_SB_DQ<0>
  VSS44  = GND
  DQ1_B  = M_C_CPU1_SB_DQ<1>
  VSS45  = GND
  DQS0_B_T  = M_C_CPU1_SB_DQS_DP<0>
  DQS0_B_C  = M_C_CPU1_SB_DQS_DN<0>
  VSS46  = GND
  DQ4_B  = M_C_CPU1_SB_DQ<4>
  VSS47  = GND
  DQ5_B  = M_C_CPU1_SB_DQ<5>
  VSS48  = GND
  DQ8_B  = M_C_CPU1_SB_DQ<8>
  VSS49  = GND
  DQ9_B  = M_C_CPU1_SB_DQ<9>
  VSS50  = GND
  DQS1_B_T  = M_C_CPU1_SB_DQS_DP<1>
  DQS1_B_C  = M_C_CPU1_SB_DQS_DN<1>
  VSS51  = GND
  DQ12_B  = M_C_CPU1_SB_DQ<12>
  VSS52  = GND
  DQ13_B  = M_C_CPU1_SB_DQ<13>
  VSS53  = GND
  DQ16_B  = M_C_CPU1_SB_DQ<16>
  VSS54  = GND
  DQ17_B  = M_C_CPU1_SB_DQ<17>
  VSS55  = GND
  DQS2_B_T  = M_C_CPU1_SB_DQS_DP<2>
  DQS2_B_C  = M_C_CPU1_SB_DQS_DN<2>
  VSS56  = GND
  DQ20_B  = M_C_CPU1_SB_DQ<20>
  VSS57  = GND
  DQ21_B  = M_C_CPU1_SB_DQ<21>
  VSS58  = GND
  DQ24_B  = M_C_CPU1_SB_DQ<24>
  VSS59  = GND
  DQ25_B  = M_C_CPU1_SB_DQ<25>
  VSS60  = GND
  DQS3_B_T  = M_C_CPU1_SB_DQS_DP<3>
  DQS3_B_C  = M_C_CPU1_SB_DQS_DN<3>
  VSS61  = GND
  DQ28_B  = M_C_CPU1_SB_DQ<28>
  VSS62  = GND
  DQ29_B  = M_C_CPU1_SB_DQ<29>
  VSS63  = GND
  RFU1  = NC
  VIN_BULK1  = P12V_MEM_CPU1
  VIN_BULK2  = P12V_MEM_CPU1
  \pwr_good||fail_n\  = PWRGD_CHC_CPU1_DIMM
  HAS  = PD_CHC_CPU1_DIMM_SAA
  RFU2  = NC
  RFU3  = NC
  VSS64  = GND
  DQ2_A  = M_C_CPU1_SA_DQ<2>
  VSS65  = GND
  DQ3_A  = M_C_CPU1_SA_DQ<3>
  VSS66  = GND
  \dqs5_a_c||tdqs5_a_c||dqs5_a_t||tdqs5_a_t\  = M_C_CPU1_SA_DQS_DN<5>
  \dqs5_a_t||tdqs5_a_t\  = M_C_CPU1_SA_DQS_DP<5>
  VSS67  = GND
  DQ6_A  = M_C_CPU1_SA_DQ<6>
  VSS68  = GND
  DQ7_A  = M_C_CPU1_SA_DQ<7>
  VSS69  = GND
  DQ10_A  = M_C_CPU1_SA_DQ<10>
  VSS70  = GND
  DQ11_A  = M_C_CPU1_SA_DQ<11>
  VSS71  = GND
  \dqs6_a_c||tdqs6_a_c||dqs6_a_t||tdqs6_a_t\  = M_C_CPU1_SA_DQS_DN<6>
  \dqs6_a_t||tdqs6_a_t\  = M_C_CPU1_SA_DQS_DP<6>
  VSS72  = GND
  DQ14_A  = M_C_CPU1_SA_DQ<14>
  VSS73  = GND
  DQ15_A  = M_C_CPU1_SA_DQ<15>
  VSS74  = GND
  DQ18_A  = M_C_CPU1_SA_DQ<18>
  VSS75  = GND
  DQ19_A  = M_C_CPU1_SA_DQ<19>
  VSS76  = GND
  \dqs7_a_c||tdqs7_a_c\  = M_C_CPU1_SA_DQS_DN<7>
  \dqs7_a_t||tdqs7_a_t\  = M_C_CPU1_SA_DQS_DP<7>
  VSS77  = GND
  DQ22_A  = M_C_CPU1_SA_DQ<22>
  VSS78  = GND
  DQ23_A  = M_C_CPU1_SA_DQ<23>
  VSS79  = GND
  DQ26_A  = M_C_CPU1_SA_DQ<26>
  VSS80  = GND
  DQ27_A  = M_C_CPU1_SA_DQ<27>
  VSS81  = GND
  \dqs8_a_c||tdqs8_a_c\  = M_C_CPU1_SA_DQS_DN<8>
  \dqs8_a_t||tdqs8_a_t\  = M_C_CPU1_SA_DQS_DP<8>
  VSS82  = GND
  DQ30_A  = M_C_CPU1_SA_DQ<30>
  VSS83  = GND
  DQ31_A  = M_C_CPU1_SA_DQ<31>
  VSS84  = GND
  CB2_A  = M_C_CPU1_SA_CB<2>
  VSS85  = GND
  CB3_A  = M_C_CPU1_SA_CB<3>
  VSS86  = GND
  \dqs9_a_c||tdqs9_a_c\  = M_C_CPU1_SA_DQS_DN<9>
  \dqs9_a_t||tdqs9_a_t\  = M_C_CPU1_SA_DQS_DP<9>
  VSS87  = GND
  CB6_A  = M_C_CPU1_SA_CB<6>
  VSS88  = GND
  CB7_A  = M_C_CPU1_SA_CB<7>
  VSS89  = GND
  RESET_N  = M_C_CPU1_RESET_N
  VSS90  = GND
  CS1_A_N  = M_C_CPU1_SA_CS_N<1>
  VSS91  = GND
  CA1_A  = M_C_CPU1_SA_CA<1>
  VSS92  = GND
  CA3_A  = M_C_CPU1_SA_CA<3>
  VSS93  = GND
  CA5_A  = M_C_CPU1_SA_CA<5>
  VSS94  = GND
  CK_T  = M_C_CPU1_CLK_DP<0>
  CK_C  = M_C_CPU1_CLK_DN<0>
  VSS95  = GND
  RFU4  = NC
  CA1_B  = M_C_CPU1_SB_CA<1>
  VSS96  = GND
  CA3_B  = M_C_CPU1_SB_CA<3>
  VSS97  = GND
  CA5_B  = M_C_CPU1_SB_CA<5>
  VSS98  = GND
  PAR_B  = M_C_CPU1_SB_PAR
  VSS99  = GND
  CS1_B_N  = M_C_CPU1_SB_CS_N<1>
  VSS100  = GND
  RFU5  = NC
  RFU6  = NC
  VSS101  = GND
  CB6_B  = M_C_CPU1_SB_CB<6>
  VSS102  = GND
  CB7_B  = M_C_CPU1_SB_CB<7>
  VSS103  = GND
  DQS4_B_C  = M_C_CPU1_SB_DQS_DN<4>
  DQS4_B_T  = M_C_CPU1_SB_DQS_DP<4>
  VSS104  = GND
  CB2_B  = M_C_CPU1_SB_CB<2>
  VSS105  = GND
  CB3_B  = M_C_CPU1_SB_CB<3>
  VSS106  = GND
  DQ2_B  = M_C_CPU1_SB_DQ<2>
  VSS107  = GND
  DQ3_B  = M_C_CPU1_SB_DQ<3>
  VSS108  = GND
  \dqs5_b_c||tdqs5_b_c\  = M_C_CPU1_SB_DQS_DN<5>
  \dqs5_b_t||tdqs5_b_t\  = M_C_CPU1_SB_DQS_DP<5>
  VSS109  = GND
  DQ6_B  = M_C_CPU1_SB_DQ<6>
  VSS110  = GND
  DQ7_B  = M_C_CPU1_SB_DQ<7>
  VSS111  = GND
  DQ10_B  = M_C_CPU1_SB_DQ<10>
  VSS112  = GND
  DQ11_B  = M_C_CPU1_SB_DQ<11>
  VSS113  = GND
  \dqs6_b_c||tdqs6_b_c\  = M_C_CPU1_SB_DQS_DN<6>
  \dqs6_b_t||tdqs6_b_t\  = M_C_CPU1_SB_DQS_DP<6>
  VSS114  = GND
  DQ14_B  = M_C_CPU1_SB_DQ<14>
  VSS115  = GND
  DQ15_B  = M_C_CPU1_SB_DQ<15>
  VSS116  = GND
  DQ18_B  = M_C_CPU1_SB_DQ<18>
  VSS117  = GND
  DQ19_B  = M_C_CPU1_SB_DQ<19>
  VSS118  = GND
  \dqs7_b_c||tdqs7_b_c\  = M_C_CPU1_SB_DQS_DN<7>
  \dqs7_b_t||tdqs7_b_t\  = M_C_CPU1_SB_DQS_DP<7>
  VSS119  = GND
  DQ22_B  = M_C_CPU1_SB_DQ<22>
  VSS120  = GND
  DQ23_B  = M_C_CPU1_SB_DQ<23>
  VSS121  = GND
  DQ26_B  = M_C_CPU1_SB_DQ<26>
  VSS122  = GND
  DQ27_B  = M_C_CPU1_SB_DQ<27>
  VSS123  = GND
  \dqs8_b_c||tdqs8_b_c\  = M_C_CPU1_SB_DQS_DN<8>
  \dqs8_b_t||tdqs8_b_t\  = M_C_CPU1_SB_DQS_DP<8>
  VSS124  = GND
  DQ30_B  = M_C_CPU1_SB_DQ<30>
  VSS125  = GND
  DQ31_B  = M_C_CPU1_SB_DQ<31>
  VSS126  = GND
  G1  = GND
  G2  = GND
  G3  = GND

(kicad_pcb
	(version 20260206)
	(generator "pcbnew")
	(generator_version "10.0")
	(general
		(thickness 1.6)
		(legacy_teardrops no)
	)
	(paper "A4")
	(title_block
		(title "04192023_DAF0TMB3IC0_F0TG_MB_C_brd_V02_OCP.brd")
		(comment 1 "Grand Teton / footprint 4188 of 8354 (J28), pads 1-46 of 291")
	)
	(layers
		(0 "F.Cu" signal "TOP")
		(4 "In1.Cu" signal "GND")
		(6 "In2.Cu" signal "IN1")
		(8 "In3.Cu" signal "GND1")
		(10 "In4.Cu" signal "IN2")
		(12 "In5.Cu" signal "GND2")
		(14 "In6.Cu" signal "IN3")
		(16 "In7.Cu" signal "GND3")
		(18 "In8.Cu" signal "VCC")
		(20 "In9.Cu" signal "VCC1")
		(22 "In10.Cu" signal "GND4")
		(24 "In11.Cu" signal "IN4")
		(26 "In12.Cu" signal "GND5")
		(28 "In13.Cu" signal "IN5")
		(30 "In14.Cu" signal "GND6")
		(32 "In15.Cu" signal "IN6")
		(34 "In16.Cu" signal "GND7")
		(2 "B.Cu" signal "BOTTOM")
		(9 "F.Adhes" user "F.Adhesive")
		(11 "B.Adhes" user "B.Adhesive")
		(13 "F.Paste" user "Package Geometry/Pastemask Top")
		(15 "B.Paste" user "Package Geometry/Pastemask Bottom")
		(5 "F.SilkS" user "Ref Des/Silkscreen Top")
		(7 "B.SilkS" user "Ref Des/Silkscreen Bottom")
		(1 "F.Mask" user "Board Geometry/Soldermask Top")
		(3 "B.Mask" user "Board Geometry/Soldermask Bottom")
		(17 "Dwgs.User" user "User.Drawings")
		(19 "Cmts.User" user "User.Comments")
		(21 "Eco1.User" user "User.Eco1")
		(23 "Eco2.User" user "User.Eco2")
		(25 "Edge.Cuts" user "Board Geometry/Outline")
		(27 "Margin" user)
		(31 "F.CrtYd" user "Package Geometry/Place Bound Top")
		(29 "B.CrtYd" user "Package Geometry/Place Bound Bottom")
		(35 "F.Fab" user "Ref Des/Assembly Top")
		(33 "B.Fab" user "Ref Des/Assembly Bottom")
	)
	(footprint ""
		(layer "F.Cu")
		(at 42.289984 -255.560322 180)
		(property "Reference" "J28"
			(at -2.876296 -82.230976 0)
			(unlocked yes)
			(layer "F.SilkS")
			(effects
				(font
					(size 0.7874 0.5842)
					(thickness 0.1524)
				)
			)
		)
		(property "Value" ""
			(at 0 0 180)
			(layer "F.Fab")
			(effects
				(font
					(size 1.27 1.27)
				)
			)
		)
		(duplicate_pad_numbers_are_jumpers no)
		(pad "1" smd rect
			(at -2.050034 -63.324994 90)
			(size 0.519938 1.4986)
			(layers "F.Cu" "F.Mask" "F.Paste")
			(net "P12V_MEM_CPU1")
		)
		(pad "2" smd rect
			(at -2.050034 -62.47511 90)
			(size 0.519938 1.4986)
			(layers "F.Cu" "F.Mask" "F.Paste")
			(net "Net_2284")
		)
		(pad "3" smd rect
			(at -2.050034 -61.624972 90)
			(size 0.519938 1.4986)
			(layers "F.Cu" "F.Mask" "F.Paste")
			(net "P3V3_AUX")
		)
		(pad "4" smd rect
			(at -2.050034 -60.775088 90)
			(size 0.519938 1.4986)
			(layers "F.Cu" "F.Mask" "F.Paste")
			(net "I3C_SPD_DDRC_CPU1_SCL")
		)
		(pad "5" smd rect
			(at -2.050034 -59.92495 90)
			(size 0.519938 1.4986)
			(layers "F.Cu" "F.Mask" "F.Paste")
			(net "I3C_SPD_DDRC_CPU1_SDA")
		)
		(pad "6" smd rect
			(at -2.050034 -59.075066 90)
			(size 0.519938 1.4986)
			(layers "F.Cu" "F.Mask" "F.Paste")
			(net "GND")
		)
		(pad "7" smd rect
			(at -2.050034 -58.224928 90)
			(size 0.519938 1.4986)
			(layers "F.Cu" "F.Mask" "F.Paste")
			(net "M_C_CPU1_SA_DQ<0>")
		)
		(pad "8" smd rect
			(at -2.050034 -57.375044 90)
			(size 0.519938 1.4986)
			(layers "F.Cu" "F.Mask" "F.Paste")
			(net "GND")
		)
		(pad "9" smd rect
			(at -2.050034 -56.524906 90)
			(size 0.519938 1.4986)
			(layers "F.Cu" "F.Mask" "F.Paste")
			(net "M_C_CPU1_SA_DQ<1>")
		)
		(pad "10" smd rect
			(at -2.050034 -55.675022 90)
			(size 0.519938 1.4986)
			(layers "F.Cu" "F.Mask" "F.Paste")
			(net "GND")
		)
		(pad "11" smd rect
			(at -2.050034 -54.824884 90)
			(size 0.519938 1.4986)
			(layers "F.Cu" "F.Mask" "F.Paste")
			(net "M_C_CPU1_SA_DQS_DP<0>")
		)
		(pad "12" smd rect
			(at -2.050034 -53.975 90)
			(size 0.519938 1.4986)
			(layers "F.Cu" "F.Mask" "F.Paste")
			(net "M_C_CPU1_SA_DQS_DN<0>")
		)
		(pad "13" smd rect
			(at -2.050034 -53.125116 90)
			(size 0.519938 1.4986)
			(layers "F.Cu" "F.Mask" "F.Paste")
			(net "GND")
		)
		(pad "14" smd rect
			(at -2.050034 -52.274978 90)
			(size 0.519938 1.4986)
			(layers "F.Cu" "F.Mask" "F.Paste")
			(net "M_C_CPU1_SA_DQ<4>")
		)
		(pad "15" smd rect
			(at -2.050034 -51.425094 90)
			(size 0.519938 1.4986)
			(layers "F.Cu" "F.Mask" "F.Paste")
			(net "GND")
		)
		(pad "16" smd rect
			(at -2.050034 -50.574956 90)
			(size 0.519938 1.4986)
			(layers "F.Cu" "F.Mask" "F.Paste")
			(net "M_C_CPU1_SA_DQ<5>")
		)
		(pad "17" smd rect
			(at -2.050034 -49.725072 90)
			(size 0.519938 1.4986)
			(layers "F.Cu" "F.Mask" "F.Paste")
			(net "GND")
		)
		(pad "18" smd rect
			(at -2.050034 -48.874934 90)
			(size 0.519938 1.4986)
			(layers "F.Cu" "F.Mask" "F.Paste")
			(net "M_C_CPU1_SA_DQ<8>")
		)
		(pad "19" smd rect
			(at -2.050034 -48.02505 90)
			(size 0.519938 1.4986)
			(layers "F.Cu" "F.Mask" "F.Paste")
			(net "GND")
		)
		(pad "20" smd rect
			(at -2.050034 -47.174912 90)
			(size 0.519938 1.4986)
			(layers "F.Cu" "F.Mask" "F.Paste")
			(net "M_C_CPU1_SA_DQ<9>")
		)
		(pad "21" smd rect
			(at -2.050034 -46.325028 90)
			(size 0.519938 1.4986)
			(layers "F.Cu" "F.Mask" "F.Paste")
			(net "GND")
		)
		(pad "22" smd rect
			(at -2.050034 -45.47489 90)
			(size 0.519938 1.4986)
			(layers "F.Cu" "F.Mask" "F.Paste")
			(net "M_C_CPU1_SA_DQS_DP<1>")
		)
		(pad "23" smd rect
			(at -2.050034 -44.625006 90)
			(size 0.519938 1.4986)
			(layers "F.Cu" "F.Mask" "F.Paste")
			(net "M_C_CPU1_SA_DQS_DN<1>")
		)
		(pad "24" smd rect
			(at -2.050034 -43.775122 90)
			(size 0.519938 1.4986)
			(layers "F.Cu" "F.Mask" "F.Paste")
			(net "GND")
		)
		(pad "25" smd rect
			(at -2.050034 -42.924984 90)
			(size 0.519938 1.4986)
			(layers "F.Cu" "F.Mask" "F.Paste")
			(net "M_C_CPU1_SA_DQ<12>")
		)
		(pad "26" smd rect
			(at -2.050034 -42.0751 90)
			(size 0.519938 1.4986)
			(layers "F.Cu" "F.Mask" "F.Paste")
			(net "GND")
		)
		(pad "27" smd rect
			(at -2.050034 -41.224962 90)
			(size 0.519938 1.4986)
			(layers "F.Cu" "F.Mask" "F.Paste")
			(net "M_C_CPU1_SA_DQ<13>")
		)
		(pad "28" smd rect
			(at -2.050034 -40.375078 90)
			(size 0.519938 1.4986)
			(layers "F.Cu" "F.Mask" "F.Paste")
			(net "GND")
		)
		(pad "29" smd rect
			(at -2.050034 -39.52494 90)
			(size 0.519938 1.4986)
			(layers "F.Cu" "F.Mask" "F.Paste")
			(net "M_C_CPU1_SA_DQ<16>")
		)
		(pad "30" smd rect
			(at -2.050034 -38.675056 90)
			(size 0.519938 1.4986)
			(layers "F.Cu" "F.Mask" "F.Paste")
			(net "GND")
		)
		(pad "31" smd rect
			(at -2.050034 -37.824918 90)
			(size 0.519938 1.4986)
			(layers "F.Cu" "F.Mask" "F.Paste")
			(net "M_C_CPU1_SA_DQ<17>")
		)
		(pad "32" smd rect
			(at -2.050034 -36.975034 90)
			(size 0.519938 1.4986)
			(layers "F.Cu" "F.Mask" "F.Paste")
			(net "GND")
		)
		(pad "33" smd rect
			(at -2.050034 -36.124896 90)
			(size 0.519938 1.4986)
			(layers "F.Cu" "F.Mask" "F.Paste")
			(net "M_C_CPU1_SA_DQS_DP<2>")
		)
		(pad "34" smd rect
			(at -2.050034 -35.275012 90)
			(size 0.519938 1.4986)
			(layers "F.Cu" "F.Mask" "F.Paste")
			(net "M_C_CPU1_SA_DQS_DN<2>")
		)
		(pad "35" smd rect
			(at -2.050034 -34.425128 90)
			(size 0.519938 1.4986)
			(layers "F.Cu" "F.Mask" "F.Paste")
			(net "GND")
		)
		(pad "36" smd rect
			(at -2.050034 -33.57499 90)
			(size 0.519938 1.4986)
			(layers "F.Cu" "F.Mask" "F.Paste")
			(net "M_C_CPU1_SA_DQ<20>")
		)
		(pad "37" smd rect
			(at -2.050034 -32.725106 90)
			(size 0.519938 1.4986)
			(layers "F.Cu" "F.Mask" "F.Paste")
			(net "GND")
		)
		(pad "38" smd rect
			(at -2.050034 -31.874968 90)
			(size 0.519938 1.4986)
			(layers "F.Cu" "F.Mask" "F.Paste")
			(net "M_C_CPU1_SA_DQ<21>")
		)
		(pad "39" smd rect
			(at -2.050034 -31.025084 90)
			(size 0.519938 1.4986)
			(layers "F.Cu" "F.Mask" "F.Paste")
			(net "GND")
		)
		(pad "40" smd rect
			(at -2.050034 -30.174946 90)
			(size 0.519938 1.4986)
			(layers "F.Cu" "F.Mask" "F.Paste")
			(net "M_C_CPU1_SA_DQ<24>")
		)
		(pad "41" smd rect
			(at -2.050034 -29.325062 90)
			(size 0.519938 1.4986)
			(layers "F.Cu" "F.Mask" "F.Paste")
			(net "GND")
		)
		(pad "42" smd rect
			(at -2.050034 -28.474924 90)
			(size 0.519938 1.4986)
			(layers "F.Cu" "F.Mask" "F.Paste")
			(net "M_C_CPU1_SA_DQ<25>")
		)
		(pad "43" smd rect
			(at -2.050034 -27.62504 90)
			(size 0.519938 1.4986)
			(layers "F.Cu" "F.Mask" "F.Paste")
			(net "GND")
		)
		(pad "44" smd rect
			(at -2.050034 -26.774902 90)
			(size 0.519938 1.4986)
			(layers "F.Cu" "F.Mask" "F.Paste")
			(net "M_C_CPU1_SA_DQS_DP<3>")
		)
		(pad "45" smd rect
			(at -2.050034 -25.925018 90)
			(size 0.519938 1.4986)
			(layers "F.Cu" "F.Mask" "F.Paste")
			(net "M_C_CPU1_SA_DQS_DN<3>")
		)
		(pad "46" smd rect
			(at -2.050034 -25.07488 90)
			(size 0.519938 1.4986)
			(layers "F.Cu" "F.Mask" "F.Paste")
			(net "GND")
		)
	)
)
